(kicad_pcb
	(version 20260206)
	(generator "pcbnew")
	(generator_version "10.0")
	(general
		(thickness 1.6)
		(legacy_teardrops no)
	)
	(paper "A4")
	(title_block
		(title "04192023_DAF0TMB3IC0_F0TG_MB_C_brd_V02_OCP.brd")
		(comment 1 "Grand Teton / footprint 2783 of 8354 (U26), pads 976-1085 of 6102")
	)
	(layers
		(0 "F.Cu" signal "TOP")
		(4 "In1.Cu" signal "GND")
		(6 "In2.Cu" signal "IN1")
		(8 "In3.Cu" signal "GND1")
		(10 "In4.Cu" signal "IN2")
		(12 "In5.Cu" signal "GND2")
		(14 "In6.Cu" signal "IN3")
		(16 "In7.Cu" signal "GND3")
		(18 "In8.Cu" signal "VCC")
		(20 "In9.Cu" signal "VCC1")
		(22 "In10.Cu" signal "GND4")
		(24 "In11.Cu" signal "IN4")
		(26 "In12.Cu" signal "GND5")
		(28 "In13.Cu" signal "IN5")
		(30 "In14.Cu" signal "GND6")
		(32 "In15.Cu" signal "IN6")
		(34 "In16.Cu" signal "GND7")
		(2 "B.Cu" signal "BOTTOM")
		(9 "F.Adhes" user "F.Adhesive")
		(11 "B.Adhes" user "B.Adhesive")
		(13 "F.Paste" user "Package Geometry/Pastemask Top")
		(15 "B.Paste" user "Package Geometry/Pastemask Bottom")
		(5 "F.SilkS" user "Ref Des/Silkscreen Top")
		(7 "B.SilkS" user "Ref Des/Silkscreen Bottom")
		(1 "F.Mask" user "Board Geometry/Soldermask Top")
		(3 "B.Mask" user "Board Geometry/Soldermask Bottom")
		(17 "Dwgs.User" user "User.Drawings")
		(19 "Cmts.User" user "User.Comments")
		(21 "Eco1.User" user "User.Eco1")
		(23 "Eco2.User" user "User.Eco2")
		(25 "Edge.Cuts" user "Board Geometry/Outline")
		(27 "Margin" user)
		(31 "F.CrtYd" user "Package Geometry/Place Bound Top")
		(29 "B.CrtYd" user "Package Geometry/Place Bound Bottom")
		(35 "F.Fab" user "Ref Des/Assembly Top")
		(33 "B.Fab" user "Ref Des/Assembly Bottom")
	)
	(footprint ""
		(layer "F.Cu")
		(at 111.927894 -258.880356 180)
		(property "Reference" "U26"
			(at -45.05579 -61.794136 0)
			(unlocked yes)
			(layer "F.SilkS")
			(effects
				(font
					(size 0.7874 0.5842)
					(thickness 0.1524)
				)
			)
		)
		(property "Value" ""
			(at 0 0 180)
			(layer "F.Fab")
			(effects
				(font
					(size 1.27 1.27)
				)
			)
		)
		(duplicate_pad_numbers_are_jumpers no)
		(pad "AN53" smd circle
			(at 13.780008 -10.889996 180)
			(size 0.450088 0.450088)
			(layers "F.Cu" "F.Mask" "F.Paste")
			(net "P5E_CPU1_G1_TX_DN<13>")
		)
		(pad "AN54" smd circle
			(at 14.720062 -10.889996 180)
			(size 0.450088 0.450088)
			(layers "F.Cu" "F.Mask" "F.Paste")
			(net "GND")
		)
		(pad "AN55" smd circle
			(at 15.660116 -10.889996 180)
			(size 0.450088 0.450088)
			(layers "F.Cu" "F.Mask" "F.Paste")
			(net "M_C_CPU1_SA_DQS_DP<9>")
		)
		(pad "AN56" smd circle
			(at 16.599916 -10.889996 180)
			(size 0.450088 0.450088)
			(layers "F.Cu" "F.Mask" "F.Paste")
			(net "GND")
		)
		(pad "AN57" smd circle
			(at 17.53997 -10.889996 180)
			(size 0.450088 0.450088)
			(layers "F.Cu" "F.Mask" "F.Paste")
			(net "M_C_CPU1_SA_CB<4>")
		)
		(pad "AN58" smd circle
			(at 18.480024 -10.889996 180)
			(size 0.450088 0.450088)
			(layers "F.Cu" "F.Mask" "F.Paste")
			(net "GND")
		)
		(pad "AN59" smd circle
			(at 19.420078 -10.889996 180)
			(size 0.450088 0.450088)
			(layers "F.Cu" "F.Mask" "F.Paste")
			(net "M_D_CPU1_SA_DQS_DP<9>")
		)
		(pad "AN60" smd circle
			(at 20.359878 -10.889996 180)
			(size 0.450088 0.450088)
			(layers "F.Cu" "F.Mask" "F.Paste")
			(net "M_D_CPU1_SA_CB<4>")
		)
		(pad "AN61" smd circle
			(at 21.299932 -10.889996 180)
			(size 0.450088 0.450088)
			(layers "F.Cu" "F.Mask" "F.Paste")
			(net "GND")
		)
		(pad "AN62" smd circle
			(at 22.239986 -10.889996 180)
			(size 0.450088 0.450088)
			(layers "F.Cu" "F.Mask" "F.Paste")
			(net "M_B_CPU1_SA_DQS_DP<9>")
		)
		(pad "AN63" smd circle
			(at 23.18004 -10.889996 180)
			(size 0.450088 0.450088)
			(layers "F.Cu" "F.Mask" "F.Paste")
			(net "GND")
		)
		(pad "AN64" smd circle
			(at 24.120094 -10.889996 180)
			(size 0.450088 0.450088)
			(layers "F.Cu" "F.Mask" "F.Paste")
			(net "M_B_CPU1_SA_CB<4>")
		)
		(pad "AN65" smd circle
			(at 25.059894 -10.889996 180)
			(size 0.450088 0.450088)
			(layers "F.Cu" "F.Mask" "F.Paste")
			(net "GND")
		)
		(pad "AN66" smd circle
			(at 25.999948 -10.889996 180)
			(size 0.450088 0.450088)
			(layers "F.Cu" "F.Mask" "F.Paste")
			(net "M_F_CPU1_SA_DQS_DP<9>")
		)
		(pad "AN67" smd circle
			(at 26.940002 -10.889996 180)
			(size 0.450088 0.450088)
			(layers "F.Cu" "F.Mask" "F.Paste")
			(net "M_F_CPU1_SA_CB<4>")
		)
		(pad "AN68" smd circle
			(at 27.880056 -10.889996 180)
			(size 0.450088 0.450088)
			(layers "F.Cu" "F.Mask" "F.Paste")
			(net "GND")
		)
		(pad "AN69" smd circle
			(at 28.82011 -10.889996 180)
			(size 0.450088 0.450088)
			(layers "F.Cu" "F.Mask" "F.Paste")
			(net "M_E_CPU1_SA_DQS_DP<9>")
		)
		(pad "AN70" smd circle
			(at 29.75991 -10.889996 180)
			(size 0.450088 0.450088)
			(layers "F.Cu" "F.Mask" "F.Paste")
			(net "GND")
		)
		(pad "AN71" smd circle
			(at 30.699964 -10.889996 180)
			(size 0.450088 0.450088)
			(layers "F.Cu" "F.Mask" "F.Paste")
			(net "M_E_CPU1_SA_CB<4>")
		)
		(pad "AN72" smd circle
			(at 31.640018 -10.889996 180)
			(size 0.450088 0.450088)
			(layers "F.Cu" "F.Mask" "F.Paste")
			(net "GND")
		)
		(pad "AN73" smd circle
			(at 32.580072 -10.889996 180)
			(size 0.450088 0.450088)
			(layers "F.Cu" "F.Mask" "F.Paste")
			(net "M_A_CPU1_SA_DQS_DP<9>")
		)
		(pad "AN74" smd circle
			(at 33.519872 -10.889996 180)
			(size 0.450088 0.450088)
			(layers "F.Cu" "F.Mask" "F.Paste")
			(net "M_A_CPU1_SA_CB<4>")
		)
		(pad "AN75" smd circle
			(at 34.459926 -10.889996 180)
			(size 0.450088 0.450088)
			(layers "F.Cu" "F.Mask" "F.Paste")
			(net "GND")
		)
		(pad "AP2" smd circle
			(at -33.690052 -10.07999 180)
			(size 0.450088 0.450088)
			(layers "F.Cu" "F.Mask" "F.Paste")
			(net "M_G_CPU1_SA_CB<6>")
		)
		(pad "AP3" smd circle
			(at -32.749998 -10.07999 180)
			(size 0.450088 0.450088)
			(layers "F.Cu" "F.Mask" "F.Paste")
			(net "GND")
		)
		(pad "AP4" smd circle
			(at -31.809944 -10.07999 180)
			(size 0.450088 0.450088)
			(layers "F.Cu" "F.Mask" "F.Paste")
			(net "M_G_CPU1_SA_CB<5>")
		)
		(pad "AP5" smd circle
			(at -30.86989 -10.07999 180)
			(size 0.450088 0.450088)
			(layers "F.Cu" "F.Mask" "F.Paste")
			(net "GND")
		)
		(pad "AP6" smd circle
			(at -29.93009 -10.07999 180)
			(size 0.450088 0.450088)
			(layers "F.Cu" "F.Mask" "F.Paste")
			(net "M_K_CPU1_SA_CB<6>")
		)
		(pad "AP7" smd circle
			(at -28.990036 -10.07999 180)
			(size 0.450088 0.450088)
			(layers "F.Cu" "F.Mask" "F.Paste")
			(net "M_K_CPU1_SA_CB<5>")
		)
		(pad "AP8" smd circle
			(at -28.049982 -10.07999 180)
			(size 0.450088 0.450088)
			(layers "F.Cu" "F.Mask" "F.Paste")
			(net "GND")
		)
		(pad "AP9" smd circle
			(at -27.109928 -10.07999 180)
			(size 0.450088 0.450088)
			(layers "F.Cu" "F.Mask" "F.Paste")
			(net "M_L_CPU1_SA_CB<6>")
		)
		(pad "AP10" smd circle
			(at -26.170128 -10.07999 180)
			(size 0.450088 0.450088)
			(layers "F.Cu" "F.Mask" "F.Paste")
			(net "GND")
		)
		(pad "AP11" smd circle
			(at -25.230074 -10.07999 180)
			(size 0.450088 0.450088)
			(layers "F.Cu" "F.Mask" "F.Paste")
			(net "M_L_CPU1_SA_CB<5>")
		)
		(pad "AP12" smd circle
			(at -24.29002 -10.07999 180)
			(size 0.450088 0.450088)
			(layers "F.Cu" "F.Mask" "F.Paste")
			(net "GND")
		)
		(pad "AP13" smd circle
			(at -23.349966 -10.07999 180)
			(size 0.450088 0.450088)
			(layers "F.Cu" "F.Mask" "F.Paste")
			(net "M_H_CPU1_SA_CB<6>")
		)
		(pad "AP14" smd circle
			(at -22.409912 -10.07999 180)
			(size 0.450088 0.450088)
			(layers "F.Cu" "F.Mask" "F.Paste")
			(net "M_H_CPU1_SA_CB<5>")
		)
		(pad "AP15" smd circle
			(at -21.470112 -10.07999 180)
			(size 0.450088 0.450088)
			(layers "F.Cu" "F.Mask" "F.Paste")
			(net "GND")
		)
		(pad "AP16" smd circle
			(at -20.530058 -10.07999 180)
			(size 0.450088 0.450088)
			(layers "F.Cu" "F.Mask" "F.Paste")
			(net "M_J_CPU1_SA_CB<6>")
		)
		(pad "AP17" smd circle
			(at -19.590004 -10.07999 180)
			(size 0.450088 0.450088)
			(layers "F.Cu" "F.Mask" "F.Paste")
			(net "GND")
		)
		(pad "AP18" smd circle
			(at -18.64995 -10.07999 180)
			(size 0.450088 0.450088)
			(layers "F.Cu" "F.Mask" "F.Paste")
			(net "M_J_CPU1_SA_CB<5>")
		)
		(pad "AP19" smd circle
			(at -17.709896 -10.07999 180)
			(size 0.450088 0.450088)
			(layers "F.Cu" "F.Mask" "F.Paste")
			(net "GND")
		)
		(pad "AP20" smd circle
			(at -16.770096 -10.07999 180)
			(size 0.450088 0.450088)
			(layers "F.Cu" "F.Mask" "F.Paste")
			(net "M_I_CPU1_SA_CB<6>")
		)
		(pad "AP21" smd circle
			(at -15.830042 -10.07999 180)
			(size 0.450088 0.450088)
			(layers "F.Cu" "F.Mask" "F.Paste")
			(net "M_I_CPU1_SA_CB<5>")
		)
		(pad "AP22" smd circle
			(at -14.889988 -10.07999 180)
			(size 0.450088 0.450088)
			(layers "F.Cu" "F.Mask" "F.Paste")
			(net "GND")
		)
		(pad "AP23" smd circle
			(at -13.949934 -10.07999 180)
			(size 0.450088 0.450088)
			(layers "F.Cu" "F.Mask" "F.Paste")
			(net "PVDDCR_CPU0_P1")
		)
		(pad "AP24" smd circle
			(at -13.00988 -10.07999 180)
			(size 0.450088 0.450088)
			(layers "F.Cu" "F.Mask" "F.Paste")
			(net "PVDDCR_CPU0_P1")
		)
		(pad "AP25" smd circle
			(at -12.07008 -10.07999 180)
			(size 0.450088 0.450088)
			(layers "F.Cu" "F.Mask" "F.Paste")
			(net "GND")
		)
		(pad "AP26" smd circle
			(at -11.130026 -10.07999 180)
			(size 0.450088 0.450088)
			(layers "F.Cu" "F.Mask" "F.Paste")
			(net "PVDDCR_CPU0_P1")
		)
		(pad "AP27" smd circle
			(at -10.189972 -10.07999 180)
			(size 0.450088 0.450088)
			(layers "F.Cu" "F.Mask" "F.Paste")
			(net "PVDDCR_CPU0_P1")
		)
		(pad "AP28" smd circle
			(at -9.249918 -10.07999 180)
			(size 0.450088 0.450088)
			(layers "F.Cu" "F.Mask" "F.Paste")
			(net "GND")
		)
		(pad "AP29" smd circle
			(at -8.310118 -10.07999 180)
			(size 0.450088 0.450088)
			(layers "F.Cu" "F.Mask" "F.Paste")
			(net "PVDDCR_CPU0_P1")
		)
		(pad "AP30" smd circle
			(at -7.370064 -10.07999 180)
			(size 0.450088 0.450088)
			(layers "F.Cu" "F.Mask" "F.Paste")
			(net "PVDDCR_CPU0_P1")
		)
		(pad "AP31" smd circle
			(at -6.43001 -10.07999 180)
			(size 0.450088 0.450088)
			(layers "F.Cu" "F.Mask" "F.Paste")
			(net "GND")
		)
		(pad "AP32" smd circle
			(at -5.489956 -10.07999 180)
			(size 0.450088 0.450088)
			(layers "F.Cu" "F.Mask" "F.Paste")
			(net "PVDDCR_CPU0_P1")
		)
		(pad "AP33" smd circle
			(at -4.549902 -10.07999 180)
			(size 0.450088 0.450088)
			(layers "F.Cu" "F.Mask" "F.Paste")
			(net "PVDDCR_CPU0_P1")
		)
		(pad "AP34" smd circle
			(at -3.610102 -10.07999 180)
			(size 0.450088 0.450088)
			(layers "F.Cu" "F.Mask" "F.Paste")
			(net "GND")
		)
		(pad "AP35" smd circle
			(at -2.670048 -10.07999 180)
			(size 0.450088 0.450088)
			(layers "F.Cu" "F.Mask" "F.Paste")
			(net "GMI_CPU0_G1_CPU1_G3_TX_DN<0>")
		)
		(pad "AP36" smd circle
			(at -1.729994 -10.07999 180)
			(size 0.450088 0.450088)
			(layers "F.Cu" "F.Mask" "F.Paste")
			(net "GMI_CPU0_G1_CPU1_G3_TX_DP<0>")
		)
		(pad "AP37" smd circle
			(at -0.78994 -10.07999 180)
			(size 0.450088 0.450088)
			(layers "F.Cu" "F.Mask" "F.Paste")
			(net "GND")
		)
		(pad "AP39" smd circle
			(at 1.089914 -10.07999 180)
			(size 0.450088 0.450088)
			(layers "F.Cu" "F.Mask" "F.Paste")
			(net "GND")
		)
		(pad "AP40" smd circle
			(at 2.029968 -10.07999 180)
			(size 0.450088 0.450088)
			(layers "F.Cu" "F.Mask" "F.Paste")
			(net "P5E_CPU1_G1_TX_DP<0>")
		)
		(pad "AP41" smd circle
			(at 2.970022 -10.07999 180)
			(size 0.450088 0.450088)
			(layers "F.Cu" "F.Mask" "F.Paste")
			(net "P5E_CPU1_G1_TX_DN<0>")
		)
		(pad "AP42" smd circle
			(at 3.910076 -10.07999 180)
			(size 0.450088 0.450088)
			(layers "F.Cu" "F.Mask" "F.Paste")
			(net "GND")
		)
		(pad "AP43" smd circle
			(at 4.849876 -10.07999 180)
			(size 0.450088 0.450088)
			(layers "F.Cu" "F.Mask" "F.Paste")
			(net "PVDDCR_CPU0_P1")
		)
		(pad "AP44" smd circle
			(at 5.78993 -10.07999 180)
			(size 0.450088 0.450088)
			(layers "F.Cu" "F.Mask" "F.Paste")
			(net "PVDDCR_CPU0_P1")
		)
		(pad "AP45" smd circle
			(at 6.729984 -10.07999 180)
			(size 0.450088 0.450088)
			(layers "F.Cu" "F.Mask" "F.Paste")
			(net "GND")
		)
		(pad "AP46" smd circle
			(at 7.670038 -10.07999 180)
			(size 0.450088 0.450088)
			(layers "F.Cu" "F.Mask" "F.Paste")
			(net "PVDDCR_CPU0_P1")
		)
		(pad "AP47" smd circle
			(at 8.610092 -10.07999 180)
			(size 0.450088 0.450088)
			(layers "F.Cu" "F.Mask" "F.Paste")
			(net "PVDDCR_CPU0_P1")
		)
		(pad "AP48" smd circle
			(at 9.549892 -10.07999 180)
			(size 0.450088 0.450088)
			(layers "F.Cu" "F.Mask" "F.Paste")
			(net "GND")
		)
		(pad "AP49" smd circle
			(at 10.489946 -10.07999 180)
			(size 0.450088 0.450088)
			(layers "F.Cu" "F.Mask" "F.Paste")
			(net "PVDDCR_CPU0_P1")
		)
		(pad "AP50" smd circle
			(at 11.43 -10.07999 180)
			(size 0.450088 0.450088)
			(layers "F.Cu" "F.Mask" "F.Paste")
			(net "PVDDCR_CPU0_P1")
		)
		(pad "AP51" smd circle
			(at 12.370054 -10.07999 180)
			(size 0.450088 0.450088)
			(layers "F.Cu" "F.Mask" "F.Paste")
			(net "GND")
		)
		(pad "AP52" smd circle
			(at 13.310108 -10.07999 180)
			(size 0.450088 0.450088)
			(layers "F.Cu" "F.Mask" "F.Paste")
			(net "PVDDCR_CPU0_P1")
		)
		(pad "AP53" smd circle
			(at 14.249908 -10.07999 180)
			(size 0.450088 0.450088)
			(layers "F.Cu" "F.Mask" "F.Paste")
			(net "PVDDCR_CPU0_P1")
		)
		(pad "AP54" smd circle
			(at 15.189962 -10.07999 180)
			(size 0.450088 0.450088)
			(layers "F.Cu" "F.Mask" "F.Paste")
			(net "GND")
		)
		(pad "AP55" smd circle
			(at 16.130016 -10.07999 180)
			(size 0.450088 0.450088)
			(layers "F.Cu" "F.Mask" "F.Paste")
			(net "M_C_CPU1_SA_CB<5>")
		)
		(pad "AP56" smd circle
			(at 17.07007 -10.07999 180)
			(size 0.450088 0.450088)
			(layers "F.Cu" "F.Mask" "F.Paste")
			(net "M_C_CPU1_SA_CB<6>")
		)
		(pad "AP57" smd circle
			(at 18.010124 -10.07999 180)
			(size 0.450088 0.450088)
			(layers "F.Cu" "F.Mask" "F.Paste")
			(net "GND")
		)
		(pad "AP58" smd circle
			(at 18.949924 -10.07999 180)
			(size 0.450088 0.450088)
			(layers "F.Cu" "F.Mask" "F.Paste")
			(net "M_D_CPU1_SA_CB<5>")
		)
		(pad "AP59" smd circle
			(at 19.889978 -10.07999 180)
			(size 0.450088 0.450088)
			(layers "F.Cu" "F.Mask" "F.Paste")
			(net "GND")
		)
		(pad "AP60" smd circle
			(at 20.830032 -10.07999 180)
			(size 0.450088 0.450088)
			(layers "F.Cu" "F.Mask" "F.Paste")
			(net "M_D_CPU1_SA_CB<6>")
		)
		(pad "AP61" smd circle
			(at 21.770086 -10.07999 180)
			(size 0.450088 0.450088)
			(layers "F.Cu" "F.Mask" "F.Paste")
			(net "GND")
		)
		(pad "AP62" smd circle
			(at 22.709886 -10.07999 180)
			(size 0.450088 0.450088)
			(layers "F.Cu" "F.Mask" "F.Paste")
			(net "M_B_CPU1_SA_CB<5>")
		)
		(pad "AP63" smd circle
			(at 23.64994 -10.07999 180)
			(size 0.450088 0.450088)
			(layers "F.Cu" "F.Mask" "F.Paste")
			(net "M_B_CPU1_SA_CB<6>")
		)
		(pad "AP64" smd circle
			(at 24.589994 -10.07999 180)
			(size 0.450088 0.450088)
			(layers "F.Cu" "F.Mask" "F.Paste")
			(net "GND")
		)
		(pad "AP65" smd circle
			(at 25.530048 -10.07999 180)
			(size 0.450088 0.450088)
			(layers "F.Cu" "F.Mask" "F.Paste")
			(net "M_F_CPU1_SA_CB<5>")
		)
		(pad "AP66" smd circle
			(at 26.470102 -10.07999 180)
			(size 0.450088 0.450088)
			(layers "F.Cu" "F.Mask" "F.Paste")
			(net "GND")
		)
		(pad "AP67" smd circle
			(at 27.409902 -10.07999 180)
			(size 0.450088 0.450088)
			(layers "F.Cu" "F.Mask" "F.Paste")
			(net "M_F_CPU1_SA_CB<6>")
		)
		(pad "AP68" smd circle
			(at 28.349956 -10.07999 180)
			(size 0.450088 0.450088)
			(layers "F.Cu" "F.Mask" "F.Paste")
			(net "GND")
		)
		(pad "AP69" smd circle
			(at 29.29001 -10.07999 180)
			(size 0.450088 0.450088)
			(layers "F.Cu" "F.Mask" "F.Paste")
			(net "M_E_CPU1_SA_CB<5>")
		)
		(pad "AP70" smd circle
			(at 30.230064 -10.07999 180)
			(size 0.450088 0.450088)
			(layers "F.Cu" "F.Mask" "F.Paste")
			(net "M_E_CPU1_SA_CB<6>")
		)
		(pad "AP71" smd circle
			(at 31.170118 -10.07999 180)
			(size 0.450088 0.450088)
			(layers "F.Cu" "F.Mask" "F.Paste")
			(net "GND")
		)
		(pad "AP72" smd circle
			(at 32.109918 -10.07999 180)
			(size 0.450088 0.450088)
			(layers "F.Cu" "F.Mask" "F.Paste")
			(net "M_A_CPU1_SA_CB<5>")
		)
		(pad "AP73" smd circle
			(at 33.049972 -10.07999 180)
			(size 0.450088 0.450088)
			(layers "F.Cu" "F.Mask" "F.Paste")
			(net "GND")
		)
		(pad "AP74" smd circle
			(at 33.990026 -10.07999 180)
			(size 0.450088 0.450088)
			(layers "F.Cu" "F.Mask" "F.Paste")
			(net "M_A_CPU1_SA_CB<6>")
		)
		(pad "AR1" smd circle
			(at -34.159952 -9.269984 180)
			(size 0.450088 0.450088)
			(layers "F.Cu" "F.Mask" "F.Paste")
			(net "GND")
		)
		(pad "AR2" smd circle
			(at -33.219898 -9.269984 180)
			(size 0.450088 0.450088)
			(layers "F.Cu" "F.Mask" "F.Paste")
			(net "M_G_CPU1_ALERT_R_N")
		)
		(pad "AR3" smd circle
			(at -32.280098 -9.269984 180)
			(size 0.450088 0.450088)
			(layers "F.Cu" "F.Mask" "F.Paste")
			(net "M_G_CPU1_SA_CB<7>")
		)
		(pad "AR4" smd circle
			(at -31.340044 -9.269984 180)
			(size 0.450088 0.450088)
			(layers "F.Cu" "F.Mask" "F.Paste")
			(net "PVDDCR_SOC_P1")
		)
		(pad "AR5" smd circle
			(at -30.39999 -9.269984 180)
			(size 0.450088 0.450088)
			(layers "F.Cu" "F.Mask" "F.Paste")
			(net "GND")
		)
		(pad "AR6" smd circle
			(at -29.459936 -9.269984 180)
			(size 0.450088 0.450088)
			(layers "F.Cu" "F.Mask" "F.Paste")
			(net "GND")
		)
		(pad "AR7" smd circle
			(at -28.519882 -9.269984 180)
			(size 0.450088 0.450088)
			(layers "F.Cu" "F.Mask" "F.Paste")
			(net "M_K_CPU1_SA_CB<7>")
		)
		(pad "AR8" smd circle
			(at -27.580082 -9.269984 180)
			(size 0.450088 0.450088)
			(layers "F.Cu" "F.Mask" "F.Paste")
			(net "GND")
		)
		(pad "AR9" smd circle
			(at -26.640028 -9.269984 180)
			(size 0.450088 0.450088)
			(layers "F.Cu" "F.Mask" "F.Paste")
			(net "GND")
		)
		(pad "AR10" smd circle
			(at -25.699974 -9.269984 180)
			(size 0.450088 0.450088)
			(layers "F.Cu" "F.Mask" "F.Paste")
			(net "M_L_CPU1_SA_CB<7>")
		)
		(pad "AR11" smd circle
			(at -24.75992 -9.269984 180)
			(size 0.450088 0.450088)
			(layers "F.Cu" "F.Mask" "F.Paste")
			(net "PVDDCR_SOC_P1")
		)
		(pad "AR12" smd circle
			(at -23.82012 -9.269984 180)
			(size 0.450088 0.450088)
			(layers "F.Cu" "F.Mask" "F.Paste")
			(net "GND")
		)
		(pad "AR13" smd circle
			(at -22.880066 -9.269984 180)
			(size 0.450088 0.450088)
			(layers "F.Cu" "F.Mask" "F.Paste")
			(net "GND")
		)
		(pad "AR14" smd circle
			(at -21.940012 -9.269984 180)
			(size 0.450088 0.450088)
			(layers "F.Cu" "F.Mask" "F.Paste")
			(net "M_H_CPU1_SA_CB<7>")
		)
		(pad "AR15" smd circle
			(at -20.999958 -9.269984 180)
			(size 0.450088 0.450088)
			(layers "F.Cu" "F.Mask" "F.Paste")
			(net "GND")
		)
	)
)
